# BASEBOARD_FAB2 (Tioga Pass) — schematic parts with pin connectivity, parts 649–804 of 4751; source: Cadence DE-HDL packaged netlist (pstxprt.dat, pstxnet.dat, pstchip.dat)

C3M41  CAP  0.22UF 16V 10% X7R  pkg 0402  page 129 : 1 = DMI_CPU0_PCH_RX_DN<1> ; 2 = DMI_CPU0_PCH_RX_C_DN<1>
C3M42  CAP_A  1.0UF 6.3V 10% X6S  pkg 0402V  page 131 : 1 = P1V05_PCH_STBY ; 2 = GND
C3M43  CAP_A  1.0UF 6.3V 10% X6S  pkg 0402V  page 131 : 1 = P1V05_PCH_STBY ; 2 = GND
C3M44  CAP  0.22UF 16V 10% X7R  pkg 0402  page 129 : 1 = DMI_CPU0_PCH_RX_DN<0> ; 2 = DMI_CPU0_PCH_RX_C_DN<0>
C3M45  CAP  0.22UF 16V 10% X7R  pkg 0402  page 129 : 1 = DMI_CPU0_PCH_RX_DN<2> ; 2 = DMI_CPU0_PCH_RX_C_DN<2>
C3M46  CAP_A  1.0UF 6.3V 10% X6S  pkg 0402V  page 194 : 1 = PVCCIOMCP_CPU0 ; 2 = GND
C3N1  CAP_A  1.0UF 6.3V 10% X6S  pkg 0402V  page 132 : 1 = PVNN_PCH_STBY ; 2 = GND
C3N2  CAP_A  1.0UF 6.3V 10% X6S  pkg 0402V  page 132 : 1 = PVNN_PCH_STBY ; 2 = GND
C3N3  CAP_A  1.0UF 6.3V 10% X6S  pkg 0402V  page 132 : 1 = PVNN_PCH_STBY ; 2 = GND
C3N4  CAP_A  1.0UF 6.3V 10% X6S  pkg 0402V  page 132 : 1 = PVNN_PCH_STBY ; 2 = GND
C3N5  CAP_A  1.0UF 6.3V 10% X6S  pkg 0402V  page 132 : 1 = PVNN_PCH_STBY ; 2 = GND
C3N6  CAP_A  1.0UF 6.3V 10% X6S  pkg 0402V  page 132 : 1 = PVNN_PCH_STBY ; 2 = GND
C3N7  CAP_A  1.0UF 6.3V 10% X6S  pkg 0402V  page 132 : 1 = PVNN_PCH_STBY ; 2 = GND
C3N8  CAP  0.22UF 16V 10% X7R  pkg 0402  page 129 : 1 = DMI_CPU0_PCH_RX_DP<3> ; 2 = DMI_CPU0_PCH_RX_C_DP<3>
C3N9  CAP  0.22UF 16V 10% X7R  pkg 0402  page 129 : 1 = DMI_CPU0_PCH_RX_DP<2> ; 2 = DMI_CPU0_PCH_RX_C_DP<2>
C3N10  CAP_A  22.0UF 4V 20% X6S  pkg 0603V  page 132 : 1 = PVNN_PCH_STBY ; 2 = GND
C3N11  CAP_A  22.0UF 4V 20% X6S  pkg 0603V  page 132 : 1 = PVNN_PCH_STBY ; 2 = GND
C3N12  CAP_A  22.0UF 4V 20% X6S  pkg 0603V  page 132 : 1 = PVNN_PCH_STBY ; 2 = GND
C3N13  CAP  0.22UF 16V 10% X7R  pkg 0402  page 129 : 1 = DMI_CPU0_PCH_RX_DN<3> ; 2 = DMI_CPU0_PCH_RX_C_DN<3>
C3N14  CAPP  470UF 2.5V 20% ALUM  pkg 3018  page 194 : 1 = PVCCIOMCP_CPU0 ; 2 = GND
C3N15  CAP_A  1.0UF 6.3V 10% X6S  pkg 0402V  page 132 : 1 = PVNN_PCH_STBY ; 2 = GND
C3N16  CAP_A  1.0UF 6.3V 10% X6S  pkg 0402V  page 132 : 1 = PVNN_PCH_STBY ; 2 = GND
C3N17  CAP_A  1.0UF 6.3V 10% X6S  pkg 0402V  page 132 : 1 = PVNN_PCH_STBY ; 2 = GND
C3N18  CAP_A  1.0UF 6.3V 10% X6S  pkg 0402V  page 132 : 1 = PVNN_PCH_STBY ; 2 = GND
C3N19  CAP_A  1.0UF 6.3V 10% X6S  pkg 0402V  page 132 : 1 = PVNN_PCH_STBY ; 2 = GND
C3N20  CAP_A  1.0UF 6.3V 10% X6S  pkg 0402V  page 132 : 1 = PVNN_PCH_STBY ; 2 = GND
C3N21  CAP_A  1.0UF 6.3V 10% X6S  pkg 0402V  page 130 : 1 = P1V8_PCH_STBY ; 2 = GND
C3N22  CAP_A  1.0UF 6.3V 10% X6S  pkg 0402V  page 130 : 1 = P1V8_PCH_STBY ; 2 = GND
C3N23  CAP_A  1.0UF 6.3V 10% X6S  pkg 0402V  page 130 : 1 = P3V3_STBY ; 2 = GND
C3N24  CAP_A  22.0UF 4V 20% X6S  pkg 0603V  page 132 : 1 = PVNN_PCH_STBY ; 2 = GND
C3N25  CAP_A  1.0UF 6.3V 10% X6S  pkg 0402V  page 130 : 1 = P1V8_PCH_STBY ; 2 = GND
C3N26  CAPP  470UF 2.5V 20% ALUM  pkg 3018  page 212 : 1 = PVCCIO_CPU0 ; 2 = GND
C3N27  CAP_A  22.0UF 4V 20% X6S  pkg 0603V  page 132 : 1 = PVNN_PCH_STBY ; 2 = GND
C3N28  CAP_A  22.0UF 4V 20% X6S  pkg 0603V  page 132 : 1 = PVNN_PCH_STBY ; 2 = GND
C3N29  CAP_A  0.1UF 16V 10% X7R  pkg 0402V  page 130 : 1 = A_PVCCRTC_EXT_CAP ; 2 = GND
C3N30  CAP_A  22.0UF 4V 20% X6S  pkg 0603V  page 132 : 1 = PVNN_PCH_STBY ; 2 = GND
C3N31  CAP_A  22.0UF 4V 20% X6S  pkg 0603V  page 132 : 1 = PVNN_PCH_STBY ; 2 = GND
C3N32  CAP_A  1.0UF 6.3V 10% X6S  pkg 0402V  page 137 : 1 = RST_SRTCRST_N ; 2 = GND
C3N33  CAP  10UF 16V 10% X6S  pkg 0805  page 212 : 1 = VR_FET_SW_P12V_STBY_PVCCIO_CPU0 ; 2 = GND
C3N34  CAP  10UF 16V 10% X6S  pkg 0805  page 212 : 1 = VR_FET_SW_P12V_STBY_PVCCIO_CPU0 ; 2 = GND
C3N35  CAPP  470UF 2.5V 20% ALUM  pkg 3018  page 212 : 1 = PVCCIO_CPU0 ; 2 = GND
C3N36  CAP  10UF 16V 10% X6S  pkg 0805  page 212 : 1 = VR_FET_SW_P12V_STBY_PVCCIO_CPU0 ; 2 = GND
C3N38  CAPP  470UF 2.5V 20% ALUM  pkg 3018  page 212 : 1 = PVCCIO_CPU0 ; 2 = GND
C3N39  CAP  220PF 50V 10% X7R  pkg 0402LF  page 211 : 1 = VR_PVCCIO_CPU0_AVSP ; 2 = VSENSE_PVCCIO_CPU0_AVSN
C3N40  CAP_A  1.0UF 6.3V 10% X6S  pkg 0402V  page 194 : 1 = PVCCIOMCP_CPU0 ; 2 = GND
C3P1  CAP_A  0.1UF 16V 10% EMPTY  pkg 0402V  page 212 : 1 = VSENSE_PVCCIO_CPU0_SKT_VSEN ; 2 = VSENSE_PVCCIO_CPU0_SKT_VRTN
C3P2  CAP_A  0.1UF 16V 10% X7R  pkg 0402V  page 211 : 1 = VR_PVCCIO_CPU0_VINSEN ; 2 = GND
C3P3  CAP_A  1.0UF 6.3V 10% X6S  pkg 0402V  page 211 : 1 = VR_PVCCIO_CPU0_VDD ; 2 = GND
C3P4  CAP_A  1.0UF 6.3V 10% X6S  pkg 0402V  page 211 : 1 = VR_PVCCIO_CPU0_VD12 ; 2 = GND
C3P5  CAP_A  0.1UF 16V 10% X7R  pkg 0402V  page 211 : 1 = VR_PVCCIO_CPU0_VD12 ; 2 = GND
C3P6  CAP  1000PF 50V 10% X7R  pkg 0402LF  page 211 : 1 = PWRGD_PVCCIO_CPU0_R ; 2 = GND
C3P7  CAP_A  0.1UF 16V 10% X7R  pkg 0402V  page 211 : 1 = VR_PVCCIO_CPU0_VDD ; 2 = GND
C3P10  CAP  0.22UF 16V 10% X7R  pkg 0402  page 107 : 1 = P3E_CPU0_PE1_SS_TXP<0> ; 2 = P3E_CPU0_PE1_SS_C_TXP<0>
C3P11  CAP  0.22UF 16V 10% X7R  pkg 0402  page 107 : 1 = P3E_CPU0_PE1_SS_TXP<0> ; 2 = P3E_CPU0_PE1_PCH_TXP<0>
C3P12  CAP  0.22UF 16V 10% X7R  pkg 0402  page 107 : 1 = P3E_CPU0_PE1_SS_TXN<0> ; 2 = P3E_CPU0_PE1_SS_C_TXN<0>
C3P13  CAP  0.22UF 16V 10% X7R  pkg 0402  page 107 : 1 = P3E_CPU0_PE1_SS_TXN<0> ; 2 = P3E_CPU0_PE1_PCH_TXN<0>
C3P14  CAP  0.22UF 16V 10% X7R  pkg 0402  page 107 : 1 = P3E_CPU0_PE1_SS_TXP<1> ; 2 = P3E_CPU0_PE1_SS_C_TXP<1>
C3P15  CAP  0.22UF 16V 10% X7R  pkg 0402  page 107 : 1 = P3E_CPU0_PE1_SS_TXP<1> ; 2 = P3E_CPU0_PE1_PCH_TXP<1>
C3P16  CAP  0.22UF 16V 10% X7R  pkg 0402  page 107 : 1 = P3E_CPU0_PE1_SS_TXN<1> ; 2 = P3E_CPU0_PE1_SS_C_TXN<1>
C3P17  CAP  0.22UF 16V 10% X7R  pkg 0402  page 107 : 1 = P3E_CPU0_PE1_SS_TXN<1> ; 2 = P3E_CPU0_PE1_PCH_TXN<1>
C3P18  CAP  0.22UF 16V 10% X7R  pkg 0402  page 107 : 1 = P3E_CPU0_PE1_SS_TXP<2> ; 2 = P3E_CPU0_PE1_PCH_TXP<2>
C3P19  CAP  0.22UF 16V 10% X7R  pkg 0402  page 107 : 1 = P3E_CPU0_PE1_SS_TXP<2> ; 2 = P3E_CPU0_PE1_SS_C_TXP<2>
C3P20  CAP  0.22UF 16V 10% X7R  pkg 0402  page 107 : 1 = P3E_CPU0_PE1_SS_TXN<2> ; 2 = P3E_CPU0_PE1_PCH_TXN<2>
C3P21  CAP  0.22UF 16V 10% X7R  pkg 0402  page 107 : 1 = P3E_CPU0_PE1_SS_TXN<2> ; 2 = P3E_CPU0_PE1_SS_C_TXN<2>
C3P22  CAP  0.22UF 16V 10% X7R  pkg 0402  page 107 : 1 = P3E_CPU0_PE1_SS_TXP<3> ; 2 = P3E_CPU0_PE1_SS_C_TXP<3>
C3P23  CAP  0.22UF 16V 10% X7R  pkg 0402  page 107 : 1 = P3E_CPU0_PE1_SS_TXP<3> ; 2 = P3E_CPU0_PE1_PCH_TXP<3>
C3P24  CAP  0.22UF 16V 10% X7R  pkg 0402  page 107 : 1 = P3E_CPU0_PE1_SS_TXN<3> ; 2 = P3E_CPU0_PE1_SS_C_TXN<3>
C3P25  CAP  0.22UF 16V 10% X7R  pkg 0402  page 107 : 1 = P3E_CPU0_PE1_SS_TXN<3> ; 2 = P3E_CPU0_PE1_PCH_TXN<3>
C3P26  CAP  0.22UF 16V 10% X7R  pkg 0402  page 107 : 1 = P3E_CPU0_PE1_SS_TXP<4> ; 2 = P3E_CPU0_PE1_SS_C_TXP<4>
C3P27  CAP  0.22UF 16V 10% X7R  pkg 0402  page 107 : 1 = P3E_CPU0_PE1_SS_TXP<4> ; 2 = P3E_CPU0_PE1_PCH_TXP<4>
C3P28  CAP  0.22UF 16V 10% X7R  pkg 0402  page 107 : 1 = P3E_CPU0_PE1_SS_TXN<4> ; 2 = P3E_CPU0_PE1_PCH_TXN<4>
C3P29  CAP  0.22UF 16V 10% X7R  pkg 0402  page 107 : 1 = P3E_CPU0_PE1_SS_TXN<4> ; 2 = P3E_CPU0_PE1_SS_C_TXN<4>
C3P30  CAP  0.22UF 16V 10% X7R  pkg 0402  page 107 : 1 = P3E_CPU0_PE1_SS_TXP<5> ; 2 = P3E_CPU0_PE1_PCH_TXP<5>
C3P31  CAP  0.22UF 16V 10% X7R  pkg 0402  page 107 : 1 = P3E_CPU0_PE1_SS_TXP<5> ; 2 = P3E_CPU0_PE1_SS_C_TXP<5>
C3P32  CAP  0.22UF 16V 10% X7R  pkg 0402  page 107 : 1 = P3E_CPU0_PE1_SS_TXN<5> ; 2 = P3E_CPU0_PE1_PCH_TXN<5>
C3P33  CAP  0.22UF 16V 10% X7R  pkg 0402  page 107 : 1 = P3E_CPU0_PE1_SS_TXN<5> ; 2 = P3E_CPU0_PE1_SS_C_TXN<5>
C3P34  CAP  0.22UF 16V 10% X7R  pkg 0402  page 107 : 1 = P3E_CPU0_PE1_SS_TXP<6> ; 2 = P3E_CPU0_PE1_SS_C_TXP<6>
C3P35  CAP  0.22UF 16V 10% X7R  pkg 0402  page 107 : 1 = P3E_CPU0_PE1_SS_TXP<6> ; 2 = P3E_CPU0_PE1_PCH_TXP<6>
C3P36  CAP  0.22UF 16V 10% X7R  pkg 0402  page 107 : 1 = P3E_CPU0_PE1_SS_TXN<6> ; 2 = P3E_CPU0_PE1_SS_C_TXN<6>
C3P37  CAP  0.22UF 16V 10% X7R  pkg 0402  page 107 : 1 = P3E_CPU0_PE1_SS_TXN<6> ; 2 = P3E_CPU0_PE1_PCH_TXN<6>
C3P38  CAP  0.22UF 16V 10% X7R  pkg 0402  page 107 : 1 = P3E_CPU0_PE1_SS_TXP<7> ; 2 = P3E_CPU0_PE1_SS_C_TXP<7>
C3P39  CAP  0.22UF 16V 10% X7R  pkg 0402  page 107 : 1 = P3E_CPU0_PE1_SS_TXP<7> ; 2 = P3E_CPU0_PE1_PCH_TXP<7>
C3P40  CAP  0.22UF 16V 10% X7R  pkg 0402  page 107 : 1 = P3E_CPU0_PE1_SS_TXN<7> ; 2 = P3E_CPU0_PE1_PCH_TXN<7>
C3P41  CAP  0.22UF 16V 10% X7R  pkg 0402  page 107 : 1 = P3E_CPU0_PE1_SS_TXN<7> ; 2 = P3E_CPU0_PE1_SS_C_TXN<7>
C3P42  CAP_A  1.0UF 6.3V 10% X6S  pkg 0402V  page 96 : 1 = P3V3_STBY ; 2 = GND
C3P43  CAP_A  0.1UF 16V 10% X7R  pkg 0402V  page 192 : 1 = P3V3_STBY ; 2 = GND
C3P44  CAP_A  0.1UF 16V 10% X7R  pkg 0402V  page 192 : 1 = P3V3_STBY ; 2 = GND
C3P45  CAP  0.047UF 25V 10% X7R  pkg 0402  page 196 : 1 = A_ADM1085_CEXT ; 2 = GND
C3P46  CAP_A  0.1UF 16V 10% X7R  pkg 0402V  page 196 : 1 = P3V3_STBY ; 2 = GND
C3P47  CAP_A  0.1UF 16V 10% X7R  pkg 0402V  page 192 : 1 = P3V3_STBY ; 2 = GND
C3P48  CAP_A  0.1UF 16V 10% X7R  pkg 0402V  page 192 : 1 = P3V3_STBY ; 2 = GND
C3P49  CAP_A  0.1UF 16V 10% X7R  pkg 0402V  page 92 : 1 = P0V7_GTL2104_VREF_1 ; 2 = GND
C3P50  CAP  1.0UF 16V 10% X6S  pkg 0402  page 92 : 1 = P3V3 ; 2 = GND
C3P51  CAP_A  0.1UF 16V 10% X7R  pkg 0402V  page 192 : 1 = P3V3_STBY ; 2 = GND
C3P52  CAP_A  0.1UF 16V 10% X7R  pkg 0402V  page 192 : 1 = P3V3_STBY ; 2 = GND
C3R1  CAP_A  0.1UF 16V 10% X7R  pkg 0402V  page 192 : 1 = P3V3_STBY ; 2 = GND
C3R2  CAP_A  0.1UF 16V 10% X7R  pkg 0402V  page 192 : 1 = P3V3_STBY ; 2 = GND
C3R3  CAP_A  0.1UF 16V 10% X7R  pkg 0402V  page 192 : 1 = P3V3_STBY ; 2 = GND
C3R4  CAPP  470UF 2.5V 20% ALUM  pkg 3018  page 194 : 1 = PVCCMCP_CPU0 ; 2 = GND
C3T1  CAP_A  47UF 4V 20% X5R  pkg 0603V  page 194 : 1 = P1V8_MCP_CPU0 ; 2 = GND
C3T2  CAP_A  47UF 4V 20% X5R  pkg 0603V  page 194 : 1 = P1V8_MCP_CPU0 ; 2 = GND
C3T3  CAPP  68UF 16V 20% TANT  pkg 3018  page 195 : 1 = P12V_STBY ; 2 = GND
C3T4  CAP_A  1.0UF 6.3V 10% X6S  pkg 0402V  page 153 : 1 = P3V3_STBY ; 2 = GND
C3T5  CAP_A  0.01UF 25V 10% X7R  pkg 0402V  page 153 : 1 = P3V3_STBY ; 2 = GND
C3T6  CAPP  68UF 16V 20% TANT  pkg 3018  page 195 : 1 = P12V_STBY ; 2 = GND
C3T7  CAP  47UF 4V 20% X6S  pkg 0805  page 231 : 1 = PVPP_ABC ; 2 = GND
C3T8  CAP  10UF 16V 10% X6S  pkg 0805  page 231 : 1 = VR_FET_SW_P12V_STBY_PVPP_ABC ; 2 = GND
C3T9  CAP  47UF 4V 20% X6S  pkg 0805  page 231 : 1 = PVPP_ABC ; 2 = GND
C3T10  CAP  1.0UF 16V 10% X6S  pkg 0402  page 231 : 1 = VR_FET_SW_P12V_STBY_PVPP_ABC ; 2 = GND
C3T11  CAP  4.7UF 6.3V 10% X6S  pkg 0603  page 231 : 1 = VR_VB_PVPP_ABC ; 2 = AGND_PVPP_ABC
C3T12  CAP  10UF 16V 10% X6S  pkg 0805  page 231 : 1 = VR_FET_SW_P12V_STBY_PVPP_ABC ; 2 = GND
C3T13  CAPP  68UF 16V 20% TANT  pkg 3018  page 195 : 1 = P12V_STBY ; 2 = GND
C3T14  CAP  10UF 16V 10% X6S  pkg 0805  page 231 : 1 = VR_FET_SW_P12V_STBY_PVPP_ABC ; 2 = GND
C3T15  CAPP  68UF 16V 20% TANT  pkg 3018  page 195 : 1 = P12V_STBY ; 2 = GND
C3U1  CAPP  470UF 2.5V 20% ALUM  pkg 3018  page 217 : 1 = PVDDQ_ABC ; 2 = GND
C3U2  CAP  10UF 16V 10% X6S  pkg 0805  page 216 : 1 = VR_FET_SW_P12V_STBY_PVDDQ_ABC ; 2 = GND
C3U3  CAP  10UF 16V 10% X6S  pkg 0805  page 216 : 1 = VR_FET_SW_P12V_STBY_PVDDQ_ABC ; 2 = GND
C3U4  CAP  10UF 16V 10% X6S  pkg 0805  page 216 : 1 = VR_FET_SW_P12V_STBY_PVDDQ_ABC ; 2 = GND
C3U5  CAPP  470UF 2.5V 20% ALUM  pkg 3018  page 217 : 1 = PVDDQ_ABC ; 2 = GND
C3U6  CAP  10UF 16V 10% X6S  pkg 0805  page 216 : 1 = VR_FET_SW_P12V_STBY_PVDDQ_ABC ; 2 = GND
C3U7  CAP  10UF 16V 10% X6S  pkg 0805  page 216 : 1 = VR_FET_SW_P12V_STBY_PVDDQ_ABC ; 2 = GND
C3U8  CAPP  470UF 2.5V 20% ALUM  pkg 3018  page 217 : 1 = PVDDQ_ABC ; 2 = GND
C3U9  CAP  10UF 16V 10% X6S  pkg 0805  page 216 : 1 = VR_FET_SW_P12V_STBY_PVDDQ_ABC ; 2 = GND
C3W1  CAP  1.0UF 6.3V 10% EMPTY  pkg 0402  page 114 : 1 = A_PCH_XCLK_BIASREF ; 2 = GND
C3W2  CAP_A  0.1UF 16V 10% X7R  pkg 0402V  page 249 : 1 = BMC_TPM_HW_C_RST ; 2 = GND
C3W3  CAP_A  22.0UF 4V 20% X6S  pkg 0603V  page 76 : 1 = PVCCMCP_CPU1 ; 2 = GND
C3W4  CAP_A  22.0UF 4V 20% X6S  pkg 0603V  page 76 : 1 = PVCCMCP_CPU1 ; 2 = GND
C4A1  CAP  22UF 4V 20% X6S  pkg 0805LF  page 222 : 1 = PVTT_DEF ; 2 = GND
C4A2  CAP  1000PF 50V 10% EMPTY  pkg 0402LF  page 222 : 1 = FM_PVTT_DEF_EN_R ; 2 = GND
C4A3  CAP  1000PF 50V 10% X7R  pkg 0402LF  page 230 : 1 = PWRGD_PVTT_KLM_CPU1_R ; 2 = GND
C4A4  CAP  10UF 16V 10% X7R  pkg 0805  page 197 : 1 = P12V_NVDIMM_DEF ; 2 = GND
C4A5  CAP_A  0.01UF 25V 10% X7R  pkg 0402V  page 54 : 1 = M_F_VREF ; 2 = GND
C4A6  CAP  1000PF 50V 10% EMPTY  pkg 0402LF  page 230 : 1 = FM_PVTT_KLM_EN_R ; 2 = GND
C4A7  CAP  4.7UF 6.3V 10% X6S  pkg 0603  page 230 : 1 = VSENSE_PVDDQ_KLM_VTT ; 2 = GND
C4A8  CAP  1.0UF 16V 10% X6S  pkg 0402  page 230 : 1 = VR_PVTT_KLM_BIAS ; 2 = GND
C4A9  CAP  1.0UF 16V 10% X6S  pkg 0402  page 222 : 1 = VR_PVTT_DEF_VREF ; 2 = GND
C4A10  CAP  1.0UF 16V 10% X6S  pkg 0402  page 222 : 1 = VR_PVTT_DEF_BIAS ; 2 = GND
C4A11  CAP  4.7UF 6.3V 10% X6S  pkg 0603  page 222 : 1 = VSENSE_PVDDQ_DEF_VTT ; 2 = GND
C4A12  CAP  1000PF 50V 10% X7R  pkg 0402LF  page 222 : 1 = PWRGD_PVTT_DEF_CPU0_R ; 2 = GND
C4A13  CAP  22UF 4V 20% X6S  pkg 0805LF  page 230 : 1 = PVTT_KLM ; 2 = GND
C4A14  CAP  1.0UF 16V 10% X6S  pkg 0402  page 230 : 1 = VR_PVTT_KLM_VREF ; 2 = GND
C4A15  CAP  10UF 4V 20% X6S  pkg 0603LF  page 230 : 1 = PVDDQ_KLM ; 2 = GND
C4A16  CAP  3300PF 50V 10% EMPTY  pkg 0402LF  page 234 : 1 = VR_PVPP_KLM_PHASE ; 2 = VR_PVPP_KLM_SNUB
C4A17  CAP  10UF 16V 10% X7R  pkg 0805  page 197 : 1 = P12V_NVDIMM_DEF ; 2 = GND
C4A18  CAP_A  0.01UF 25V 10% X7R  pkg 0402V  page 52 : 1 = M_E_VREF ; 2 = GND
C4A19  CAP  10UF 16V 10% X6S  pkg 0805  page 234 : 1 = VR_FET_SW_P12V_STBY_PVPP_KLM ; 2 = GND
C4A20  CAP_A  0.1UF 16V 10% X7R  pkg 0402V  page 234 : 1 = VR_FET_SW_P12V_STBY_PVPP_KLM ; 2 = GND
C4B1  SC22U16V5MX-4-GP  20%  pkg SMD-BCG5  page 234 : 1 = VR_FET_SW_P12V_STBY_PVPP_KLM ; 2 = GND
C4B2  CAP  47UF 4V 20% X6S  pkg 0805  page 234 : 1 = PVPP_KLM ; 2 = GND
C4B3  CAP  47UF 4V 20% X6S  pkg 0805  page 234 : 1 = PVPP_KLM ; 2 = GND
C4B4  CAP  100.0PF 50V 5% COG  pkg 0402LF  page 234 : 1 = VR_FB_PVPP_KLM ; 2 = VR_COMP_PVPP_KLM_3
C4B5  CAP  1000PF 50V 10% EMPTY  pkg 0402LF  page 234 : 1 = FM_PVPP_CPU1_EN ; 2 = AGND_PVPP_KLM
C4B6  CAP  0.027UF 16V 10% X7R  pkg 0402  page 234 : 1 = VR_PVPP_KLM_SS ; 2 = AGND_PVPP_KLM
C4B7  CAP  2200PF 50V 10% X7R  pkg 0402LF  page 234 : 1 = VR_COMP_PVPP_KLM ; 2 = VR_FB_PVPP_KLM
C4B8  CAP  1000PF 50V 10% X7R  pkg 0402LF  page 234 : 1 = PWRGD_PVPP_KLM_R ; 2 = GND
C4B9  CAP  2200PF 50V 10% X7R  pkg 0402LF  page 234 : 1 = VR_COMP_RC_PVPP_KLM ; 2 = VR_COMP_PVPP_KLM_3
